(kicad_pcb
	(version 20260206)
	(generator "pcbnew")
	(generator_version "10.0")
	(general
		(thickness 1.6)
		(legacy_teardrops no)
	)
	(paper "A4")
	(title_block
		(title "04192023_DAF0TMB3IC0_F0TG_MB_C_brd_V02_OCP.brd")
		(comment 1 "Grand Teton / footprints 3735-3740 of 8354")
	)
	(layers
		(0 "F.Cu" signal "TOP")
		(4 "In1.Cu" signal "GND")
		(6 "In2.Cu" signal "IN1")
		(8 "In3.Cu" signal "GND1")
		(10 "In4.Cu" signal "IN2")
		(12 "In5.Cu" signal "GND2")
		(14 "In6.Cu" signal "IN3")
		(16 "In7.Cu" signal "GND3")
		(18 "In8.Cu" signal "VCC")
		(20 "In9.Cu" signal "VCC1")
		(22 "In10.Cu" signal "GND4")
		(24 "In11.Cu" signal "IN4")
		(26 "In12.Cu" signal "GND5")
		(28 "In13.Cu" signal "IN5")
		(30 "In14.Cu" signal "GND6")
		(32 "In15.Cu" signal "IN6")
		(34 "In16.Cu" signal "GND7")
		(2 "B.Cu" signal "BOTTOM")
		(9 "F.Adhes" user "F.Adhesive")
		(11 "B.Adhes" user "B.Adhesive")
		(13 "F.Paste" user "Package Geometry/Pastemask Top")
		(15 "B.Paste" user "Package Geometry/Pastemask Bottom")
		(5 "F.SilkS" user "Ref Des/Silkscreen Top")
		(7 "B.SilkS" user "Ref Des/Silkscreen Bottom")
		(1 "F.Mask" user "Board Geometry/Soldermask Top")
		(3 "B.Mask" user "Board Geometry/Soldermask Bottom")
		(17 "Dwgs.User" user "User.Drawings")
		(19 "Cmts.User" user "User.Comments")
		(21 "Eco1.User" user "User.Eco1")
		(23 "Eco2.User" user "User.Eco2")
		(25 "Edge.Cuts" user "Board Geometry/Outline")
		(27 "Margin" user)
		(31 "F.CrtYd" user "Package Geometry/Place Bound Top")
		(29 "B.CrtYd" user "Package Geometry/Place Bound Bottom")
		(35 "F.Fab" user "Ref Des/Assembly Top")
		(33 "B.Fab" user "Ref Des/Assembly Bottom")
	)
	(footprint ""
		(layer "F.Cu")
		(at 179.058062 -32.935672 90)
		(property "Reference" "PC2229"
			(at 0 0 90)
			(layer "F.SilkS")
			(hide yes)
			(effects
				(font
					(size 1.27 1.27)
				)
			)
		)
		(property "Value" ""
			(at 0 0 90)
			(layer "F.Fab")
			(effects
				(font
					(size 1.27 1.27)
				)
			)
		)
		(duplicate_pad_numbers_are_jumpers no)
		(fp_line
			(start 0.7874 -0.4064)
			(end 0.7874 0.4064)
			(stroke
				(width 0.1524)
				(type default)
			)
			(layer "F.SilkS")
		)
		(fp_line
			(start -0.7874 -0.4064)
			(end 0.7874 -0.4064)
			(stroke
				(width 0.1524)
				(type default)
			)
			(layer "F.SilkS")
		)
		(fp_line
			(start 0.7874 0.4064)
			(end -0.7874 0.4064)
			(stroke
				(width 0.1524)
				(type default)
			)
			(layer "F.SilkS")
		)
		(fp_line
			(start -0.7874 0.4064)
			(end -0.7874 -0.4064)
			(stroke
				(width 0.1524)
				(type default)
			)
			(layer "F.SilkS")
		)
		(fp_line
			(start -0.12065 -0.305054)
			(end -0.12065 -0.2794)
			(stroke
				(width 0.1)
				(type default)
			)
			(layer "F.Fab")
		)
		(fp_line
			(start -0.67945 -0.305054)
			(end -0.12065 -0.305054)
			(stroke
				(width 0.1)
				(type default)
			)
			(layer "F.Fab")
		)
		(fp_line
			(start 0.67945 -0.3048)
			(end 0.67945 0.3048)
			(stroke
				(width 0.1)
				(type default)
			)
			(layer "F.Fab")
		)
		(fp_line
			(start 0.12065 -0.3048)
			(end 0.67945 -0.3048)
			(stroke
				(width 0.1)
				(type default)
			)
			(layer "F.Fab")
		)
		(fp_line
			(start 0.12065 -0.2794)
			(end 0.12065 -0.3048)
			(stroke
				(width 0.1)
				(type default)
			)
			(layer "F.Fab")
		)
		(fp_line
			(start -0.12065 -0.2794)
			(end 0.12065 -0.2794)
			(stroke
				(width 0.1)
				(type default)
			)
			(layer "F.Fab")
		)
		(fp_line
			(start 0.120396 0.2794)
			(end -0.12065 0.2794)
			(stroke
				(width 0.1)
				(type default)
			)
			(layer "F.Fab")
		)
		(fp_line
			(start -0.12065 0.2794)
			(end -0.12065 0.3048)
			(stroke
				(width 0.1)
				(type default)
			)
			(layer "F.Fab")
		)
		(fp_line
			(start 0.67945 0.3048)
			(end 0.120396 0.3048)
			(stroke
				(width 0.1)
				(type default)
			)
			(layer "F.Fab")
		)
		(fp_line
			(start 0.120396 0.3048)
			(end 0.120396 0.2794)
			(stroke
				(width 0.1)
				(type default)
			)
			(layer "F.Fab")
		)
		(fp_line
			(start -0.12065 0.3048)
			(end -0.67945 0.3048)
			(stroke
				(width 0.1)
				(type default)
			)
			(layer "F.Fab")
		)
		(fp_line
			(start -0.67945 0.3048)
			(end -0.67945 -0.305054)
			(stroke
				(width 0.1)
				(type default)
			)
			(layer "F.Fab")
		)
		(pad "1" smd circle
			(at -0.40005 0 90)
			(size 0 0)
			(layers "F.Cu" "F.Mask" "F.Paste")
			(net "P12V_SCM_TIMER")
		)
		(pad "2" smd circle
			(at 0.40005 0 90)
			(size 0 0)
			(layers "F.Cu" "F.Mask" "F.Paste")
			(net "GND")
		)
	)
	(footprint ""
		(layer "F.Cu")
		(at 277.352252 -111.91367)
		(property "Reference" "R3535"
			(at 0 0 0)
			(layer "F.SilkS")
			(hide yes)
			(effects
				(font
					(size 1.27 1.27)
				)
			)
		)
		(property "Value" ""
			(at 0 0 0)
			(layer "F.Fab")
			(effects
				(font
					(size 1.27 1.27)
				)
			)
		)
		(duplicate_pad_numbers_are_jumpers no)
		(fp_line
			(start -0.7874 -0.4064)
			(end 0.7874 -0.4064)
			(stroke
				(width 0.1524)
				(type default)
			)
			(layer "F.SilkS")
		)
		(fp_line
			(start -0.7874 0.4064)
			(end -0.7874 -0.4064)
			(stroke
				(width 0.1524)
				(type default)
			)
			(layer "F.SilkS")
		)
		(fp_line
			(start 0.7874 -0.4064)
			(end 0.7874 0.4064)
			(stroke
				(width 0.1524)
				(type default)
			)
			(layer "F.SilkS")
		)
		(fp_line
			(start 0.7874 0.4064)
			(end -0.7874 0.4064)
			(stroke
				(width 0.1524)
				(type default)
			)
			(layer "F.SilkS")
		)
		(fp_line
			(start -0.67945 -0.305054)
			(end -0.12065 -0.305054)
			(stroke
				(width 0.1)
				(type default)
			)
			(layer "F.Fab")
		)
		(fp_line
			(start -0.67945 0.3048)
			(end -0.67945 -0.305054)
			(stroke
				(width 0.1)
				(type default)
			)
			(layer "F.Fab")
		)
		(fp_line
			(start -0.12065 -0.305054)
			(end -0.12065 -0.2794)
			(stroke
				(width 0.1)
				(type default)
			)
			(layer "F.Fab")
		)
		(fp_line
			(start -0.12065 -0.2794)
			(end 0.12065 -0.2794)
			(stroke
				(width 0.1)
				(type default)
			)
			(layer "F.Fab")
		)
		(fp_line
			(start -0.12065 0.2794)
			(end -0.12065 0.3048)
			(stroke
				(width 0.1)
				(type default)
			)
			(layer "F.Fab")
		)
		(fp_line
			(start -0.12065 0.3048)
			(end -0.67945 0.3048)
			(stroke
				(width 0.1)
				(type default)
			)
			(layer "F.Fab")
		)
		(fp_line
			(start 0.120396 0.2794)
			(end -0.12065 0.2794)
			(stroke
				(width 0.1)
				(type default)
			)
			(layer "F.Fab")
		)
		(fp_line
			(start 0.120396 0.3048)
			(end 0.120396 0.2794)
			(stroke
				(width 0.1)
				(type default)
			)
			(layer "F.Fab")
		)
		(fp_line
			(start 0.12065 -0.3048)
			(end 0.67945 -0.3048)
			(stroke
				(width 0.1)
				(type default)
			)
			(layer "F.Fab")
		)
		(fp_line
			(start 0.12065 -0.2794)
			(end 0.12065 -0.3048)
			(stroke
				(width 0.1)
				(type default)
			)
			(layer "F.Fab")
		)
		(fp_line
			(start 0.67945 -0.3048)
			(end 0.67945 0.3048)
			(stroke
				(width 0.1)
				(type default)
			)
			(layer "F.Fab")
		)
		(fp_line
			(start 0.67945 0.3048)
			(end 0.120396 0.3048)
			(stroke
				(width 0.1)
				(type default)
			)
			(layer "F.Fab")
		)
		(pad "1" smd circle
			(at -0.40005 0)
			(size 0 0)
			(layers "F.Cu" "F.Mask" "F.Paste")
			(net "P3V3_AUX")
		)
		(pad "2" smd circle
			(at 0.40005 0)
			(size 0 0)
			(layers "F.Cu" "F.Mask" "F.Paste")
			(net "SMB_SENSOR_E1S_3V3AUX_SCL")
		)
	)
	(footprint ""
		(layer "F.Cu")
		(at 270.192754 -418.971476 90)
		(property "Reference" "C2179"
			(at 0 0 90)
			(layer "F.SilkS")
			(hide yes)
			(effects
				(font
					(size 1.27 1.27)
				)
			)
		)
		(property "Value" ""
			(at 0 0 90)
			(layer "F.Fab")
			(effects
				(font
					(size 1.27 1.27)
				)
			)
		)
		(duplicate_pad_numbers_are_jumpers no)
		(fp_line
			(start 0.7874 -0.4064)
			(end 0.7874 0.4064)
			(stroke
				(width 0.1524)
				(type default)
			)
			(layer "F.SilkS")
		)
		(fp_line
			(start -0.7874 -0.4064)
			(end 0.7874 -0.4064)
			(stroke
				(width 0.1524)
				(type default)
			)
			(layer "F.SilkS")
		)
		(fp_line
			(start 0.7874 0.4064)
			(end -0.7874 0.4064)
			(stroke
				(width 0.1524)
				(type default)
			)
			(layer "F.SilkS")
		)
		(fp_line
			(start -0.7874 0.4064)
			(end -0.7874 -0.4064)
			(stroke
				(width 0.1524)
				(type default)
			)
			(layer "F.SilkS")
		)
		(fp_line
			(start -0.12065 -0.305054)
			(end -0.12065 -0.2794)
			(stroke
				(width 0.1)
				(type default)
			)
			(layer "F.Fab")
		)
		(fp_line
			(start -0.67945 -0.305054)
			(end -0.12065 -0.305054)
			(stroke
				(width 0.1)
				(type default)
			)
			(layer "F.Fab")
		)
		(fp_line
			(start 0.67945 -0.3048)
			(end 0.67945 0.3048)
			(stroke
				(width 0.1)
				(type default)
			)
			(layer "F.Fab")
		)
		(fp_line
			(start 0.12065 -0.3048)
			(end 0.67945 -0.3048)
			(stroke
				(width 0.1)
				(type default)
			)
			(layer "F.Fab")
		)
		(fp_line
			(start 0.12065 -0.2794)
			(end 0.12065 -0.3048)
			(stroke
				(width 0.1)
				(type default)
			)
			(layer "F.Fab")
		)
		(fp_line
			(start -0.12065 -0.2794)
			(end 0.12065 -0.2794)
			(stroke
				(width 0.1)
				(type default)
			)
			(layer "F.Fab")
		)
		(fp_line
			(start 0.120396 0.2794)
			(end -0.12065 0.2794)
			(stroke
				(width 0.1)
				(type default)
			)
			(layer "F.Fab")
		)
		(fp_line
			(start -0.12065 0.2794)
			(end -0.12065 0.3048)
			(stroke
				(width 0.1)
				(type default)
			)
			(layer "F.Fab")
		)
		(fp_line
			(start 0.67945 0.3048)
			(end 0.120396 0.3048)
			(stroke
				(width 0.1)
				(type default)
			)
			(layer "F.Fab")
		)
		(fp_line
			(start 0.120396 0.3048)
			(end 0.120396 0.2794)
			(stroke
				(width 0.1)
				(type default)
			)
			(layer "F.Fab")
		)
		(fp_line
			(start -0.12065 0.3048)
			(end -0.67945 0.3048)
			(stroke
				(width 0.1)
				(type default)
			)
			(layer "F.Fab")
		)
		(fp_line
			(start -0.67945 0.3048)
			(end -0.67945 -0.305054)
			(stroke
				(width 0.1)
				(type default)
			)
			(layer "F.Fab")
		)
		(pad "1" smd circle
			(at -0.40005 0 90)
			(size 0 0)
			(layers "F.Cu" "F.Mask" "F.Paste")
			(net "HSC_EN")
		)
		(pad "2" smd circle
			(at 0.40005 0 90)
			(size 0 0)
			(layers "F.Cu" "F.Mask" "F.Paste")
			(net "GND")
		)
	)
	(footprint ""
		(layer "F.Cu")
		(at 427.975268 -58.397648 90)
		(property "Reference" "C693"
			(at 0 0 90)
			(layer "F.SilkS")
			(hide yes)
			(effects
				(font
					(size 1.27 1.27)
				)
			)
		)
		(property "Value" ""
			(at 0 0 90)
			(layer "F.Fab")
			(effects
				(font
					(size 1.27 1.27)
				)
			)
		)
		(duplicate_pad_numbers_are_jumpers no)
		(fp_line
			(start 0.7874 -0.4064)
			(end 0.7874 0.4064)
			(stroke
				(width 0.1524)
				(type default)
			)
			(layer "F.SilkS")
		)
		(fp_line
			(start -0.7874 -0.4064)
			(end 0.7874 -0.4064)
			(stroke
				(width 0.1524)
				(type default)
			)
			(layer "F.SilkS")
		)
		(fp_line
			(start 0.7874 0.4064)
			(end -0.7874 0.4064)
			(stroke
				(width 0.1524)
				(type default)
			)
			(layer "F.SilkS")
		)
		(fp_line
			(start -0.7874 0.4064)
			(end -0.7874 -0.4064)
			(stroke
				(width 0.1524)
				(type default)
			)
			(layer "F.SilkS")
		)
		(fp_line
			(start -0.12065 -0.305054)
			(end -0.12065 -0.2794)
			(stroke
				(width 0.1)
				(type default)
			)
			(layer "F.Fab")
		)
		(fp_line
			(start -0.67945 -0.305054)
			(end -0.12065 -0.305054)
			(stroke
				(width 0.1)
				(type default)
			)
			(layer "F.Fab")
		)
		(fp_line
			(start 0.67945 -0.3048)
			(end 0.67945 0.3048)
			(stroke
				(width 0.1)
				(type default)
			)
			(layer "F.Fab")
		)
		(fp_line
			(start 0.12065 -0.3048)
			(end 0.67945 -0.3048)
			(stroke
				(width 0.1)
				(type default)
			)
			(layer "F.Fab")
		)
		(fp_line
			(start 0.12065 -0.2794)
			(end 0.12065 -0.3048)
			(stroke
				(width 0.1)
				(type default)
			)
			(layer "F.Fab")
		)
		(fp_line
			(start -0.12065 -0.2794)
			(end 0.12065 -0.2794)
			(stroke
				(width 0.1)
				(type default)
			)
			(layer "F.Fab")
		)
		(fp_line
			(start 0.120396 0.2794)
			(end -0.12065 0.2794)
			(stroke
				(width 0.1)
				(type default)
			)
			(layer "F.Fab")
		)
		(fp_line
			(start -0.12065 0.2794)
			(end -0.12065 0.3048)
			(stroke
				(width 0.1)
				(type default)
			)
			(layer "F.Fab")
		)
		(fp_line
			(start 0.67945 0.3048)
			(end 0.120396 0.3048)
			(stroke
				(width 0.1)
				(type default)
			)
			(layer "F.Fab")
		)
		(fp_line
			(start 0.120396 0.3048)
			(end 0.120396 0.2794)
			(stroke
				(width 0.1)
				(type default)
			)
			(layer "F.Fab")
		)
		(fp_line
			(start -0.12065 0.3048)
			(end -0.67945 0.3048)
			(stroke
				(width 0.1)
				(type default)
			)
			(layer "F.Fab")
		)
		(fp_line
			(start -0.67945 0.3048)
			(end -0.67945 -0.305054)
			(stroke
				(width 0.1)
				(type default)
			)
			(layer "F.Fab")
		)
		(pad "1" smd circle
			(at -0.40005 0 90)
			(size 0 0)
			(layers "F.Cu" "F.Mask" "F.Paste")
			(net "U124_VCC")
		)
		(pad "2" smd circle
			(at 0.40005 0 90)
			(size 0 0)
			(layers "F.Cu" "F.Mask" "F.Paste")
			(net "GND")
		)
	)
	(footprint ""
		(layer "F.Cu")
		(at 5.35432 -74.719688)
		(property "Reference" "U241"
			(at -2.3876 -2.250948 0)
			(unlocked yes)
			(layer "F.SilkS")
			(effects
				(font
					(size 0.7874 0.5842)
					(thickness 0.1524)
				)
				(justify left)
			)
		)
		(property "Value" ""
			(at 0 0 0)
			(layer "F.Fab")
			(effects
				(font
					(size 1.27 1.27)
				)
			)
		)
		(duplicate_pad_numbers_are_jumpers no)
		(fp_line
			(start -1.207008 -1.549908)
			(end -1.207008 1.549908)
			(stroke
				(width 0.1524)
				(type default)
			)
			(layer "F.SilkS")
		)
		(fp_line
			(start -1.207008 1.549908)
			(end 1.207008 1.549908)
			(stroke
				(width 0.1524)
				(type default)
			)
			(layer "F.SilkS")
		)
		(fp_line
			(start -0.762508 -1.549908)
			(end -1.207008 -1.549908)
			(stroke
				(width 0.1524)
				(type default)
			)
			(layer "F.SilkS")
		)
		(fp_line
			(start 0 -0.635)
			(end -0.762508 -1.549908)
			(stroke
				(width 0.1524)
				(type default)
			)
			(layer "F.SilkS")
		)
		(fp_line
			(start 0.762508 -1.549908)
			(end 0 -0.635)
			(stroke
				(width 0.1524)
				(type default)
			)
			(layer "F.SilkS")
		)
		(fp_line
			(start 1.207008 -1.549908)
			(end 0.762508 -1.549908)
			(stroke
				(width 0.1524)
				(type default)
			)
			(layer "F.SilkS")
		)
		(fp_line
			(start 1.207008 1.549908)
			(end 1.207008 -1.549908)
			(stroke
				(width 0.1524)
				(type default)
			)
			(layer "F.SilkS")
		)
		(fp_poly
			(pts
				(xy -2.3876 -1.02489) (xy -3.4036 -0.51689) (xy -3.4036 -1.53289)
			)
			(stroke
				(width 0)
				(type default)
			)
			(fill yes)
			(layer "F.SilkS")
		)
		(fp_line
			(start -1.549908 -1.549908)
			(end -1.549908 1.549908)
			(stroke
				(width 0.1)
				(type default)
			)
			(layer "F.Fab")
		)
		(fp_line
			(start -1.549908 1.549908)
			(end 1.549908 1.549908)
			(stroke
				(width 0.1)
				(type default)
			)
			(layer "F.Fab")
		)
		(fp_line
			(start 1.549908 -1.549908)
			(end -1.549908 -1.549908)
			(stroke
				(width 0.1)
				(type default)
			)
			(layer "F.Fab")
		)
		(fp_line
			(start 1.549908 1.549908)
			(end 1.549908 -1.549908)
			(stroke
				(width 0.1)
				(type default)
			)
			(layer "F.Fab")
		)
		(fp_poly
			(pts
				(xy -3.4036 -1.53289) (xy -3.4036 -0.51689) (xy -2.3876 -1.02489)
			)
			(stroke
				(width 0)
				(type default)
			)
			(fill yes)
			(layer "F.Fab")
		)
		(pad "1" smd rect
			(at -1.774952 -1.02489 270)
			(size 0.508 0.8636)
			(layers "F.Cu" "F.Mask" "F.Paste")
			(net "OCP_V3_2_PRSNT0_R_N")
		)
		(pad "2" smd rect
			(at -1.774952 -0.32512 270)
			(size 0.4064 0.8636)
			(layers "F.Cu" "F.Mask" "F.Paste")
			(net "OCP_V3_2_PRSNT1_R_N")
		)
		(pad "3" smd rect
			(at -1.774952 0.32512 270)
			(size 0.4064 0.8636)
			(layers "F.Cu" "F.Mask" "F.Paste")
			(net "OCP_V3_2_PRSNT23_R_N")
		)
		(pad "4" smd rect
			(at -1.774952 1.02489 270)
			(size 0.508 0.8636)
			(layers "F.Cu" "F.Mask" "F.Paste")
			(net "GND")
		)
		(pad "5" smd rect
			(at 1.774952 1.02489 270)
			(size 0.508 0.8636)
			(layers "F.Cu" "F.Mask" "F.Paste")
			(net "OCP_V3_2_PRSNT2_R_N")
		)
		(pad "6" smd rect
			(at 1.774952 0.32512 270)
			(size 0.4064 0.8636)
			(layers "F.Cu" "F.Mask" "F.Paste")
			(net "OCP_V3_2_PRSNT3_R_N")
		)
		(pad "7" smd rect
			(at 1.774952 -0.32512 270)
			(size 0.4064 0.8636)
			(layers "F.Cu" "F.Mask" "F.Paste")
			(net "OCP_V3_2_PRSNT01_R_N")
		)
		(pad "8" smd rect
			(at 1.774952 -1.02489 270)
			(size 0.508 0.8636)
			(layers "F.Cu" "F.Mask" "F.Paste")
			(net "P3V3_AUX")
		)
	)
	(footprint ""
		(layer "F.Cu")
		(at 12.96416 -71.210678)
		(property "Reference" "U59"
			(at -1.2065 1.973072 0)
			(unlocked yes)
			(layer "F.SilkS")
			(effects
				(font
					(size 0.7874 0.5842)
					(thickness 0.1524)
				)
				(justify left)
			)
		)
		(property "Value" ""
			(at 0 0 0)
			(layer "F.Fab")
			(effects
				(font
					(size 1.27 1.27)
				)
			)
		)
		(duplicate_pad_numbers_are_jumpers no)
		(fp_line
			(start -1.38176 -1.100074)
			(end -1.38176 1.100074)
			(stroke
				(width 0.1524)
				(type default)
			)
			(layer "F.SilkS")
		)
		(fp_line
			(start -1.38176 1.100074)
			(end 1.38176 1.100074)
			(stroke
				(width 0.1524)
				(type default)
			)
			(layer "F.SilkS")
		)
		(fp_line
			(start -0.592074 -1.100074)
			(end -1.38176 -1.100074)
			(stroke
				(width 0.1524)
				(type default)
			)
			(layer "F.SilkS")
		)
		(fp_line
			(start 0 -0.508)
			(end -0.592074 -1.100074)
			(stroke
				(width 0.1524)
				(type default)
			)
			(layer "F.SilkS")
		)
		(fp_line
			(start 0.592074 -1.100074)
			(end 0 -0.508)
			(stroke
				(width 0.1524)
				(type default)
			)
			(layer "F.SilkS")
		)
		(fp_line
			(start 1.38176 -1.100074)
			(end 0.592074 -1.100074)
			(stroke
				(width 0.1524)
				(type default)
			)
			(layer "F.SilkS")
		)
		(fp_line
			(start 1.38176 1.100074)
			(end 1.38176 -1.100074)
			(stroke
				(width 0.1524)
				(type default)
			)
			(layer "F.SilkS")
		)
		(fp_poly
			(pts
				(xy -1.9431 -0.429768) (xy -1.9431 -0.870204) (xy -1.50241 -0.649986)
			)
			(stroke
				(width 0)
				(type default)
			)
			(fill yes)
			(layer "F.SilkS")
		)
		(fp_line
			(start -0.674878 -1.100074)
			(end -0.674878 1.100074)
			(stroke
				(width 0.1)
				(type default)
			)
			(layer "F.Fab")
		)
		(fp_line
			(start -0.674878 1.100074)
			(end 0.674878 1.100074)
			(stroke
				(width 0.1)
				(type default)
			)
			(layer "F.Fab")
		)
		(fp_line
			(start 0.674878 -1.100074)
			(end -0.674878 -1.100074)
			(stroke
				(width 0.1)
				(type default)
			)
			(layer "F.Fab")
		)
		(fp_line
			(start 0.674878 1.100074)
			(end 0.674878 -1.100074)
			(stroke
				(width 0.1)
				(type default)
			)
			(layer "F.Fab")
		)
		(fp_poly
			(pts
				(xy -1.9431 -0.870204) (xy -1.50241 -0.649986) (xy -1.9431 -0.429768)
			)
			(stroke
				(width 0)
				(type default)
			)
			(fill yes)
			(layer "F.Fab")
		)
		(pad "1" smd rect
			(at -0.94996 -0.649986 270)
			(size 0.4318 0.6096)
			(layers "F.Cu" "F.Mask" "F.Paste")
			(net "OCP_V3_2_PRSNT2_R_N")
		)
		(pad "2" smd rect
			(at -0.94996 0 270)
			(size 0.4318 0.6096)
			(layers "F.Cu" "F.Mask" "F.Paste")
			(net "GND")
		)
		(pad "3" smd rect
			(at -0.94996 0.649986 270)
			(size 0.4318 0.6096)
			(layers "F.Cu" "F.Mask" "F.Paste")
			(net "OCP_V3_2_PRSNT3_R_N")
		)
		(pad "4" smd rect
			(at 0.94996 0.649986 270)
			(size 0.4318 0.6096)
			(layers "F.Cu" "F.Mask" "F.Paste")
			(net "HP_LVC3_OCP_V3_2_PRSNT2_N_R")
		)
		(pad "5" smd rect
			(at 0.94996 0 270)
			(size 0.4318 0.6096)
			(layers "F.Cu" "F.Mask" "F.Paste")
			(net "P3V3_AUX")
		)
		(pad "6" smd rect
			(at 0.94996 -0.649986 270)
			(size 0.4318 0.6096)
			(layers "F.Cu" "F.Mask" "F.Paste")
			(net "HP_LVC3_OCP_V3_2_PRSNT2_N_R")
		)
	)
)
